(kicad_pcb
	(version 20260206)
	(generator "pcbnew")
	(generator_version "10.0")
	(general
		(thickness 1.6)
		(legacy_teardrops no)
	)
	(paper "A4")
	(title_block
		(title "01162023_DA0F0TEBIF0_F0T_Expander_BD_F_brd_V02_OCP.brd")
		(comment 1 "Grand Teton / footprints 2159-2163 of 9728")
	)
	(layers
		(0 "F.Cu" signal "TOP")
		(4 "In1.Cu" signal "GND")
		(6 "In2.Cu" signal "VCC")
		(8 "In3.Cu" signal "VCC1")
		(10 "In4.Cu" signal "GND1")
		(12 "In5.Cu" signal "IN1")
		(14 "In6.Cu" signal "GND2")
		(16 "In7.Cu" signal "IN2")
		(18 "In8.Cu" signal "GND3")
		(20 "In9.Cu" signal "IN3")
		(22 "In10.Cu" signal "GND4")
		(24 "In11.Cu" signal "IN4")
		(26 "In12.Cu" signal "GND5")
		(28 "In13.Cu" signal "IN5")
		(30 "In14.Cu" signal "GND6")
		(32 "In15.Cu" signal "IN6")
		(34 "In16.Cu" signal "GND7")
		(2 "B.Cu" signal "BOTTOM")
		(9 "F.Adhes" user "F.Adhesive")
		(11 "B.Adhes" user "B.Adhesive")
		(13 "F.Paste" user "Package Geometry/Pastemask Top")
		(15 "B.Paste" user "Package Geometry/Pastemask Bottom")
		(5 "F.SilkS" user "Ref Des/Silkscreen Top")
		(7 "B.SilkS" user "Ref Des/Silkscreen Bottom")
		(1 "F.Mask" user "Board Geometry/Soldermask Top")
		(3 "B.Mask" user "Board Geometry/Soldermask Bottom")
		(17 "Dwgs.User" user "User.Drawings")
		(19 "Cmts.User" user "User.Comments")
		(21 "Eco1.User" user "User.Eco1")
		(23 "Eco2.User" user "User.Eco2")
		(25 "Edge.Cuts" user "Board Geometry/Outline")
		(27 "Margin" user)
		(31 "F.CrtYd" user "Package Geometry/Place Bound Top")
		(29 "B.CrtYd" user "Package Geometry/Place Bound Bottom")
		(35 "F.Fab" user "Ref Des/Assembly Top")
		(33 "B.Fab" user "Ref Des/Assembly Bottom")
	)
	(footprint ""
		(layer "F.Cu")
		(at 242.025932 -280.10104 180)
		(property "Reference" "C628"
			(at 0 0 180)
			(layer "F.SilkS")
			(hide yes)
			(effects
				(font
					(size 1.27 1.27)
				)
			)
		)
		(property "Value" ""
			(at 0 0 180)
			(layer "F.Fab")
			(effects
				(font
					(size 1.27 1.27)
				)
			)
		)
		(duplicate_pad_numbers_are_jumpers no)
		(fp_line
			(start 0.7874 0.4064)
			(end -0.7874 0.4064)
			(stroke
				(width 0.1524)
				(type default)
			)
			(layer "F.SilkS")
		)
		(fp_line
			(start 0.7874 -0.4064)
			(end 0.7874 0.4064)
			(stroke
				(width 0.1524)
				(type default)
			)
			(layer "F.SilkS")
		)
		(fp_line
			(start -0.7874 0.4064)
			(end -0.7874 -0.4064)
			(stroke
				(width 0.1524)
				(type default)
			)
			(layer "F.SilkS")
		)
		(fp_line
			(start -0.7874 -0.4064)
			(end 0.7874 -0.4064)
			(stroke
				(width 0.1524)
				(type default)
			)
			(layer "F.SilkS")
		)
		(fp_line
			(start 0.67945 0.3048)
			(end 0.120396 0.3048)
			(stroke
				(width 0.1)
				(type default)
			)
			(layer "F.Fab")
		)
		(fp_line
			(start 0.67945 -0.3048)
			(end 0.67945 0.3048)
			(stroke
				(width 0.1)
				(type default)
			)
			(layer "F.Fab")
		)
		(fp_line
			(start 0.12065 -0.2794)
			(end 0.12065 -0.3048)
			(stroke
				(width 0.1)
				(type default)
			)
			(layer "F.Fab")
		)
		(fp_line
			(start 0.12065 -0.3048)
			(end 0.67945 -0.3048)
			(stroke
				(width 0.1)
				(type default)
			)
			(layer "F.Fab")
		)
		(fp_line
			(start 0.120396 0.3048)
			(end 0.120396 0.2794)
			(stroke
				(width 0.1)
				(type default)
			)
			(layer "F.Fab")
		)
		(fp_line
			(start 0.120396 0.2794)
			(end -0.12065 0.2794)
			(stroke
				(width 0.1)
				(type default)
			)
			(layer "F.Fab")
		)
		(fp_line
			(start -0.12065 0.3048)
			(end -0.67945 0.3048)
			(stroke
				(width 0.1)
				(type default)
			)
			(layer "F.Fab")
		)
		(fp_line
			(start -0.12065 0.2794)
			(end -0.12065 0.3048)
			(stroke
				(width 0.1)
				(type default)
			)
			(layer "F.Fab")
		)
		(fp_line
			(start -0.12065 -0.2794)
			(end 0.12065 -0.2794)
			(stroke
				(width 0.1)
				(type default)
			)
			(layer "F.Fab")
		)
		(fp_line
			(start -0.12065 -0.305054)
			(end -0.12065 -0.2794)
			(stroke
				(width 0.1)
				(type default)
			)
			(layer "F.Fab")
		)
		(fp_line
			(start -0.67945 0.3048)
			(end -0.67945 -0.305054)
			(stroke
				(width 0.1)
				(type default)
			)
			(layer "F.Fab")
		)
		(fp_line
			(start -0.67945 -0.305054)
			(end -0.12065 -0.305054)
			(stroke
				(width 0.1)
				(type default)
			)
			(layer "F.Fab")
		)
		(pad "1" smd circle
			(at -0.40005 0 180)
			(size 0 0)
			(layers "F.Cu" "F.Mask" "F.Paste")
			(net "P3V3_AUX")
		)
		(pad "2" smd circle
			(at 0.40005 0 180)
			(size 0 0)
			(layers "F.Cu" "F.Mask" "F.Paste")
			(net "GND")
		)
	)
	(footprint ""
		(layer "F.Cu")
		(at 192.900808 -410.296868 90)
		(property "Reference" "C2846"
			(at 0 0 90)
			(layer "F.SilkS")
			(hide yes)
			(effects
				(font
					(size 1.27 1.27)
				)
			)
		)
		(property "Value" ""
			(at 0 0 90)
			(layer "F.Fab")
			(effects
				(font
					(size 1.27 1.27)
				)
			)
		)
		(duplicate_pad_numbers_are_jumpers no)
		(fp_line
			(start 0.7874 -0.4064)
			(end 0.7874 0.4064)
			(stroke
				(width 0.1524)
				(type default)
			)
			(layer "F.SilkS")
		)
		(fp_line
			(start -0.7874 -0.4064)
			(end 0.7874 -0.4064)
			(stroke
				(width 0.1524)
				(type default)
			)
			(layer "F.SilkS")
		)
		(fp_line
			(start 0.7874 0.4064)
			(end -0.7874 0.4064)
			(stroke
				(width 0.1524)
				(type default)
			)
			(layer "F.SilkS")
		)
		(fp_line
			(start -0.7874 0.4064)
			(end -0.7874 -0.4064)
			(stroke
				(width 0.1524)
				(type default)
			)
			(layer "F.SilkS")
		)
		(fp_line
			(start -0.12065 -0.305054)
			(end -0.12065 -0.2794)
			(stroke
				(width 0.1)
				(type default)
			)
			(layer "F.Fab")
		)
		(fp_line
			(start -0.67945 -0.305054)
			(end -0.12065 -0.305054)
			(stroke
				(width 0.1)
				(type default)
			)
			(layer "F.Fab")
		)
		(fp_line
			(start 0.67945 -0.3048)
			(end 0.67945 0.3048)
			(stroke
				(width 0.1)
				(type default)
			)
			(layer "F.Fab")
		)
		(fp_line
			(start 0.12065 -0.3048)
			(end 0.67945 -0.3048)
			(stroke
				(width 0.1)
				(type default)
			)
			(layer "F.Fab")
		)
		(fp_line
			(start 0.12065 -0.2794)
			(end 0.12065 -0.3048)
			(stroke
				(width 0.1)
				(type default)
			)
			(layer "F.Fab")
		)
		(fp_line
			(start -0.12065 -0.2794)
			(end 0.12065 -0.2794)
			(stroke
				(width 0.1)
				(type default)
			)
			(layer "F.Fab")
		)
		(fp_line
			(start 0.120396 0.2794)
			(end -0.12065 0.2794)
			(stroke
				(width 0.1)
				(type default)
			)
			(layer "F.Fab")
		)
		(fp_line
			(start -0.12065 0.2794)
			(end -0.12065 0.3048)
			(stroke
				(width 0.1)
				(type default)
			)
			(layer "F.Fab")
		)
		(fp_line
			(start 0.67945 0.3048)
			(end 0.120396 0.3048)
			(stroke
				(width 0.1)
				(type default)
			)
			(layer "F.Fab")
		)
		(fp_line
			(start 0.120396 0.3048)
			(end 0.120396 0.2794)
			(stroke
				(width 0.1)
				(type default)
			)
			(layer "F.Fab")
		)
		(fp_line
			(start -0.12065 0.3048)
			(end -0.67945 0.3048)
			(stroke
				(width 0.1)
				(type default)
			)
			(layer "F.Fab")
		)
		(fp_line
			(start -0.67945 0.3048)
			(end -0.67945 -0.305054)
			(stroke
				(width 0.1)
				(type default)
			)
			(layer "F.Fab")
		)
		(pad "1" smd circle
			(at -0.40005 0 90)
			(size 0 0)
			(layers "F.Cu" "F.Mask" "F.Paste")
			(net "P3V3_AUX")
		)
		(pad "2" smd circle
			(at 0.40005 0 90)
			(size 0 0)
			(layers "F.Cu" "F.Mask" "F.Paste")
			(net "GND")
		)
	)
	(footprint ""
		(layer "F.Cu")
		(at 46.952154 -84.960968)
		(property "Reference" "H142"
			(at -1.551686 -3.452622 0)
			(unlocked yes)
			(layer "F.SilkS")
			(effects
				(font
					(size 0.7874 0.5842)
					(thickness 0.1524)
				)
				(justify left)
			)
		)
		(property "Value" ""
			(at 0 0 0)
			(layer "F.Fab")
			(effects
				(font
					(size 1.27 1.27)
				)
			)
		)
		(duplicate_pad_numbers_are_jumpers no)
		(fp_circle
			(center 0 0)
			(end 2.4003 0)
			(stroke
				(width 0.1524)
				(type default)
			)
			(fill no)
			(layer "F.SilkS")
		)
		(fp_circle
			(center 0 0)
			(end 6.5913 0)
			(stroke
				(width 0.1524)
				(type default)
			)
			(fill no)
			(layer "B.SilkS")
		)
		(fp_circle
			(center 0 0)
			(end 6.5913 0)
			(stroke
				(width 0.1)
				(type default)
			)
			(fill no)
			(layer "B.Fab")
		)
		(fp_circle
			(center 0 0)
			(end 2.4003 0)
			(stroke
				(width 0.1)
				(type default)
			)
			(fill no)
			(layer "F.Fab")
		)
		(pad "" np_thru_hole circle
			(at 0 0)
			(size 3.175 3.175)
			(drill 3.175)
			(layers "*.Cu" "*.Mask")
			(clearance 0.381)
			(thermal_gap 0.381)
		)
		(zone
			(layers "F.Cu" "B.Cu" "In1.Cu" "In2.Cu" "In3.Cu" "In4.Cu" "In5.Cu" "In6.Cu"
				"In7.Cu" "In8.Cu" "In9.Cu" "In10.Cu" "In11.Cu" "In12.Cu" "In13.Cu" "In14.Cu"
				"In15.Cu" "In16.Cu"
			)
			(hatch none 0.5)
			(connect_pads
				(clearance 0)
			)
			(min_thickness 0.25)
			(keepout
				(tracks not_allowed)
				(vias allowed)
				(pads allowed)
				(copperpour not_allowed)
				(footprints allowed)
			)
			(placement
				(enabled no)
				(sheetname "")
			)
			(fill
				(thermal_gap 0.5)
				(thermal_bridge_width 0.5)
				(island_removal_mode 0)
			)
			(polygon
				(pts
					(arc
						(start 49.047654 -84.960968)
						(mid 44.856654 -84.960968)
						(end 49.047654 -84.960968)
					)
				)
			)
		)
	)
	(footprint ""
		(layer "F.Cu")
		(at 305.489864 -72.766682 90)
		(property "Reference" "PR7082"
			(at 0 0 90)
			(layer "F.SilkS")
			(hide yes)
			(effects
				(font
					(size 1.27 1.27)
				)
			)
		)
		(property "Value" ""
			(at 0 0 90)
			(layer "F.Fab")
			(effects
				(font
					(size 1.27 1.27)
				)
			)
		)
		(duplicate_pad_numbers_are_jumpers no)
		(fp_line
			(start 0.7874 -0.4064)
			(end 0.7874 0.4064)
			(stroke
				(width 0.1524)
				(type default)
			)
			(layer "F.SilkS")
		)
		(fp_line
			(start -0.7874 -0.4064)
			(end 0.7874 -0.4064)
			(stroke
				(width 0.1524)
				(type default)
			)
			(layer "F.SilkS")
		)
		(fp_line
			(start 0.7874 0.4064)
			(end -0.7874 0.4064)
			(stroke
				(width 0.1524)
				(type default)
			)
			(layer "F.SilkS")
		)
		(fp_line
			(start -0.7874 0.4064)
			(end -0.7874 -0.4064)
			(stroke
				(width 0.1524)
				(type default)
			)
			(layer "F.SilkS")
		)
		(fp_line
			(start -0.12065 -0.305054)
			(end -0.12065 -0.2794)
			(stroke
				(width 0.1)
				(type default)
			)
			(layer "F.Fab")
		)
		(fp_line
			(start -0.67945 -0.305054)
			(end -0.12065 -0.305054)
			(stroke
				(width 0.1)
				(type default)
			)
			(layer "F.Fab")
		)
		(fp_line
			(start 0.67945 -0.3048)
			(end 0.67945 0.3048)
			(stroke
				(width 0.1)
				(type default)
			)
			(layer "F.Fab")
		)
		(fp_line
			(start 0.12065 -0.3048)
			(end 0.67945 -0.3048)
			(stroke
				(width 0.1)
				(type default)
			)
			(layer "F.Fab")
		)
		(fp_line
			(start 0.12065 -0.2794)
			(end 0.12065 -0.3048)
			(stroke
				(width 0.1)
				(type default)
			)
			(layer "F.Fab")
		)
		(fp_line
			(start -0.12065 -0.2794)
			(end 0.12065 -0.2794)
			(stroke
				(width 0.1)
				(type default)
			)
			(layer "F.Fab")
		)
		(fp_line
			(start 0.120396 0.2794)
			(end -0.12065 0.2794)
			(stroke
				(width 0.1)
				(type default)
			)
			(layer "F.Fab")
		)
		(fp_line
			(start -0.12065 0.2794)
			(end -0.12065 0.3048)
			(stroke
				(width 0.1)
				(type default)
			)
			(layer "F.Fab")
		)
		(fp_line
			(start 0.67945 0.3048)
			(end 0.120396 0.3048)
			(stroke
				(width 0.1)
				(type default)
			)
			(layer "F.Fab")
		)
		(fp_line
			(start 0.120396 0.3048)
			(end 0.120396 0.2794)
			(stroke
				(width 0.1)
				(type default)
			)
			(layer "F.Fab")
		)
		(fp_line
			(start -0.12065 0.3048)
			(end -0.67945 0.3048)
			(stroke
				(width 0.1)
				(type default)
			)
			(layer "F.Fab")
		)
		(fp_line
			(start -0.67945 0.3048)
			(end -0.67945 -0.305054)
			(stroke
				(width 0.1)
				(type default)
			)
			(layer "F.Fab")
		)
		(pad "1" smd circle
			(at -0.40005 0 90)
			(size 0 0)
			(layers "F.Cu" "F.Mask" "F.Paste")
			(net "P12V_SSD10_CO_ILIMIT")
		)
		(pad "2" smd circle
			(at 0.40005 0 90)
			(size 0 0)
			(layers "F.Cu" "F.Mask" "F.Paste")
			(net "GND")
		)
	)
	(footprint ""
		(layer "F.Cu")
		(at 373.507 -210.185)
		(property "Reference" "U343"
			(at -1.3462 -4.613148 0)
			(unlocked yes)
			(layer "F.SilkS")
			(effects
				(font
					(size 0.7874 0.5842)
					(thickness 0.1524)
				)
				(justify left)
			)
		)
		(property "Value" ""
			(at 0 0 0)
			(layer "F.Fab")
			(effects
				(font
					(size 1.27 1.27)
				)
			)
		)
		(duplicate_pad_numbers_are_jumpers no)
		(fp_line
			(start -2.097532 -3.949954)
			(end -2.097532 3.949954)
			(stroke
				(width 0.1524)
				(type default)
			)
			(layer "F.SilkS")
		)
		(fp_line
			(start -2.097532 3.949954)
			(end 2.097532 3.949954)
			(stroke
				(width 0.1524)
				(type default)
			)
			(layer "F.SilkS")
		)
		(fp_line
			(start -1.409954 -3.949954)
			(end -2.097532 -3.949954)
			(stroke
				(width 0.1524)
				(type default)
			)
			(layer "F.SilkS")
		)
		(fp_line
			(start 0 -2.54)
			(end -1.409954 -3.949954)
			(stroke
				(width 0.1524)
				(type default)
			)
			(layer "F.SilkS")
		)
		(fp_line
			(start 1.409954 -3.949954)
			(end 0 -2.54)
			(stroke
				(width 0.1524)
				(type default)
			)
			(layer "F.SilkS")
		)
		(fp_line
			(start 2.097532 -3.949954)
			(end 1.409954 -3.949954)
			(stroke
				(width 0.1524)
				(type default)
			)
			(layer "F.SilkS")
		)
		(fp_line
			(start 2.097532 3.949954)
			(end 2.097532 -3.949954)
			(stroke
				(width 0.1524)
				(type default)
			)
			(layer "F.SilkS")
		)
		(fp_poly
			(pts
				(xy -4.7498 -4.182872) (xy -4.7498 -3.166872) (xy -3.7338 -3.674872)
			)
			(stroke
				(width 0)
				(type default)
			)
			(fill yes)
			(layer "F.SilkS")
		)
		(fp_line
			(start -2.249932 -3.949954)
			(end -2.249932 3.949954)
			(stroke
				(width 0.1)
				(type default)
			)
			(layer "F.Fab")
		)
		(fp_line
			(start -2.249932 3.949954)
			(end 2.249932 3.949954)
			(stroke
				(width 0.1)
				(type default)
			)
			(layer "F.Fab")
		)
		(fp_line
			(start 2.249932 -3.949954)
			(end -2.249932 -3.949954)
			(stroke
				(width 0.1)
				(type default)
			)
			(layer "F.Fab")
		)
		(fp_line
			(start 2.249932 3.949954)
			(end 2.249932 -3.949954)
			(stroke
				(width 0.1)
				(type default)
			)
			(layer "F.Fab")
		)
		(fp_poly
			(pts
				(xy -4.7498 -4.182872) (xy -4.7498 -3.166872) (xy -3.7338 -3.674872)
			)
			(stroke
				(width 0)
				(type default)
			)
			(fill yes)
			(layer "F.Fab")
		)
		(pad "1" smd rect
			(at -2.925064 -3.674872 270)
			(size 0.6096 1.3716)
			(layers "F.Cu" "F.Mask" "F.Paste")
			(net "PEX0_PCA9555_0_INT_N")
		)
		(pad "2" smd rect
			(at -2.925064 -2.925064 270)
			(size 0.4064 1.3716)
			(layers "F.Cu" "F.Mask" "F.Paste")
			(net "PCA9555_0_PEX0_A1")
		)
		(pad "3" smd rect
			(at -2.925064 -2.275078 270)
			(size 0.4064 1.3716)
			(layers "F.Cu" "F.Mask" "F.Paste")
			(net "PCA9555_0_PEX0_A2")
		)
		(pad "4" smd rect
			(at -2.925064 -1.625092 270)
			(size 0.4064 1.3716)
			(layers "F.Cu" "F.Mask" "F.Paste")
			(net "PRSNT_SSD0_FPGA_PCA9555_N")
		)
		(pad "5" smd rect
			(at -2.925064 -0.975106 270)
			(size 0.4064 1.3716)
			(layers "F.Cu" "F.Mask" "F.Paste")
			(net "SSD0_PEX_PWR_EN")
		)
		(pad "6" smd rect
			(at -2.925064 -0.32512 270)
			(size 0.4064 1.3716)
			(layers "F.Cu" "F.Mask" "F.Paste")
			(net "RST_PEX_SSD0_PERST_N")
		)
		(pad "7" smd rect
			(at -2.925064 0.32512 270)
			(size 0.4064 1.3716)
			(layers "F.Cu" "F.Mask" "F.Paste")
			(net "Net_1186")
		)
		(pad "8" smd rect
			(at -2.925064 0.975106 270)
			(size 0.4064 1.3716)
			(layers "F.Cu" "F.Mask" "F.Paste")
			(net "PRSNT_SSD1_FPGA_PCA9555_N")
		)
		(pad "9" smd rect
			(at -2.925064 1.625092 270)
			(size 0.4064 1.3716)
			(layers "F.Cu" "F.Mask" "F.Paste")
			(net "SSD1_PEX_PWR_EN")
		)
		(pad "10" smd rect
			(at -2.925064 2.275078 270)
			(size 0.4064 1.3716)
			(layers "F.Cu" "F.Mask" "F.Paste")
			(net "RST_PEX_SSD1_PERST_N")
		)
		(pad "11" smd rect
			(at -2.925064 2.925064 270)
			(size 0.4064 1.3716)
			(layers "F.Cu" "F.Mask" "F.Paste")
			(net "Net_1187")
		)
		(pad "12" smd rect
			(at -2.925064 3.674872 270)
			(size 0.6096 1.3716)
			(layers "F.Cu" "F.Mask" "F.Paste")
			(net "GND")
		)
		(pad "13" smd rect
			(at 2.925064 3.674872 270)
			(size 0.6096 1.3716)
			(layers "F.Cu" "F.Mask" "F.Paste")
			(net "PRSNT_NIC0_FPGA_PCA9555_N")
		)
		(pad "14" smd rect
			(at 2.925064 2.925064 270)
			(size 0.4064 1.3716)
			(layers "F.Cu" "F.Mask" "F.Paste")
			(net "NIC0_PEX_PWR_EN")
		)
		(pad "15" smd rect
			(at 2.925064 2.275078 270)
			(size 0.4064 1.3716)
			(layers "F.Cu" "F.Mask" "F.Paste")
			(net "RST_PEX_NIC0_PERST_N")
		)
		(pad "16" smd rect
			(at 2.925064 1.625092 270)
			(size 0.4064 1.3716)
			(layers "F.Cu" "F.Mask" "F.Paste")
			(net "Net_1188")
		)
		(pad "17" smd rect
			(at 2.925064 0.975106 270)
			(size 0.4064 1.3716)
			(layers "F.Cu" "F.Mask" "F.Paste")
			(net "Net_8992")
		)
		(pad "18" smd rect
			(at 2.925064 0.32512 270)
			(size 0.4064 1.3716)
			(layers "F.Cu" "F.Mask" "F.Paste")
			(net "Net_8991")
		)
		(pad "19" smd rect
			(at 2.925064 -0.32512 270)
			(size 0.4064 1.3716)
			(layers "F.Cu" "F.Mask" "F.Paste")
			(net "Net_8990")
		)
		(pad "20" smd rect
			(at 2.925064 -0.975106 270)
			(size 0.4064 1.3716)
			(layers "F.Cu" "F.Mask" "F.Paste")
			(net "Net_8989")
		)
		(pad "21" smd rect
			(at 2.925064 -1.625092 270)
			(size 0.4064 1.3716)
			(layers "F.Cu" "F.Mask" "F.Paste")
			(net "PCA9555_0_PEX0_A0")
		)
		(pad "22" smd rect
			(at 2.925064 -2.275078 270)
			(size 0.4064 1.3716)
			(layers "F.Cu" "F.Mask" "F.Paste")
			(net "SMB_PEX0_PCA9555_SCL")
		)
		(pad "23" smd rect
			(at 2.925064 -2.925064 270)
			(size 0.4064 1.3716)
			(layers "F.Cu" "F.Mask" "F.Paste")
			(net "SMB_PEX0_PCA9555_SDA")
		)
		(pad "24" smd rect
			(at 2.925064 -3.674872 270)
			(size 0.6096 1.3716)
			(layers "F.Cu" "F.Mask" "F.Paste")
			(net "P3V3_AUX")
		)
	)
)
